(kicad_pcb
	(version 20260206)
	(generator "pcbnew")
	(generator_version "10.0")
	(general
		(thickness 1.6)
		(legacy_teardrops no)
	)
	(paper "A4")
	(title_block
		(title "04192023_DAF0TMB3IC0_F0TG_MB_C_brd_V02_OCP.brd")
		(comment 1 "Grand Teton / footprints 447-450 of 8354")
	)
	(layers
		(0 "F.Cu" signal "TOP")
		(4 "In1.Cu" signal "GND")
		(6 "In2.Cu" signal "IN1")
		(8 "In3.Cu" signal "GND1")
		(10 "In4.Cu" signal "IN2")
		(12 "In5.Cu" signal "GND2")
		(14 "In6.Cu" signal "IN3")
		(16 "In7.Cu" signal "GND3")
		(18 "In8.Cu" signal "VCC")
		(20 "In9.Cu" signal "VCC1")
		(22 "In10.Cu" signal "GND4")
		(24 "In11.Cu" signal "IN4")
		(26 "In12.Cu" signal "GND5")
		(28 "In13.Cu" signal "IN5")
		(30 "In14.Cu" signal "GND6")
		(32 "In15.Cu" signal "IN6")
		(34 "In16.Cu" signal "GND7")
		(2 "B.Cu" signal "BOTTOM")
		(9 "F.Adhes" user "F.Adhesive")
		(11 "B.Adhes" user "B.Adhesive")
		(13 "F.Paste" user "Package Geometry/Pastemask Top")
		(15 "B.Paste" user "Package Geometry/Pastemask Bottom")
		(5 "F.SilkS" user "Ref Des/Silkscreen Top")
		(7 "B.SilkS" user "Ref Des/Silkscreen Bottom")
		(1 "F.Mask" user "Board Geometry/Soldermask Top")
		(3 "B.Mask" user "Board Geometry/Soldermask Bottom")
		(17 "Dwgs.User" user "User.Drawings")
		(19 "Cmts.User" user "User.Comments")
		(21 "Eco1.User" user "User.Eco1")
		(23 "Eco2.User" user "User.Eco2")
		(25 "Edge.Cuts" user "Board Geometry/Outline")
		(27 "Margin" user)
		(31 "F.CrtYd" user "Package Geometry/Place Bound Top")
		(29 "B.CrtYd" user "Package Geometry/Place Bound Bottom")
		(35 "F.Fab" user "Ref Des/Assembly Top")
		(33 "B.Fab" user "Ref Des/Assembly Bottom")
	)
	(footprint ""
		(layer "F.Cu")
		(at 220.872558 -401.920202 180)
		(property "Reference" "PU296"
			(at 2.818384 -5.05206 90)
			(unlocked yes)
			(layer "F.SilkS")
			(effects
				(font
					(size 0.7874 0.5842)
					(thickness 0.1524)
				)
			)
		)
		(property "Value" ""
			(at 0 0 180)
			(layer "F.Fab")
			(effects
				(font
					(size 1.27 1.27)
				)
			)
		)
		(duplicate_pad_numbers_are_jumpers no)
		(fp_line
			(start 2.567686 2.567686)
			(end 2.567686 -2.567686)
			(stroke
				(width 0.1524)
				(type default)
			)
			(layer "F.SilkS")
		)
		(fp_line
			(start 2.567686 -2.567686)
			(end -2.567686 -2.567686)
			(stroke
				(width 0.1524)
				(type default)
			)
			(layer "F.SilkS")
		)
		(fp_line
			(start -2.567686 2.567686)
			(end 2.567686 2.567686)
			(stroke
				(width 0.1524)
				(type default)
			)
			(layer "F.SilkS")
		)
		(fp_line
			(start -2.567686 -2.567686)
			(end -2.567686 2.567686)
			(stroke
				(width 0.1524)
				(type default)
			)
			(layer "F.SilkS")
		)
		(fp_poly
			(pts
				(xy -2.632456 -2.13233) (xy -3.709924 -2.491486) (xy -2.991612 -3.209798)
			)
			(stroke
				(width 0)
				(type default)
			)
			(fill yes)
			(layer "F.SilkS")
		)
		(fp_line
			(start 2.549906 2.549906)
			(end 2.549906 -2.549906)
			(stroke
				(width 0.1)
				(type default)
			)
			(layer "F.Fab")
		)
		(fp_line
			(start 2.549906 -2.549906)
			(end -2.549906 -2.549906)
			(stroke
				(width 0.1)
				(type default)
			)
			(layer "F.Fab")
		)
		(fp_line
			(start -2.549906 2.549906)
			(end 2.549906 2.549906)
			(stroke
				(width 0.1)
				(type default)
			)
			(layer "F.Fab")
		)
		(fp_line
			(start -2.549906 -2.549906)
			(end -2.549906 2.549906)
			(stroke
				(width 0.1)
				(type default)
			)
			(layer "F.Fab")
		)
		(fp_poly
			(pts
				(xy -3.806698 -2.25806) (xy -3.806698 -1.24206) (xy -2.790698 -1.75006)
			)
			(stroke
				(width 0)
				(type default)
			)
			(fill yes)
			(layer "F.Fab")
		)
		(pad "1" smd rect
			(at -2.250186 -1.75006 270)
			(size 0.254 0.3556)
			(layers "F.Cu" "F.Mask" "F.Paste")
			(net "P12V_AUX")
		)
		(pad "2" smd rect
			(at -2.237486 -1.249934 270)
			(size 0.254 0.381)
			(layers "F.Cu" "F.Mask" "F.Paste")
			(net "P12V_AUX")
		)
		(pad "3" smd rect
			(at -2.237486 -0.750062 270)
			(size 0.254 0.381)
			(layers "F.Cu" "F.Mask" "F.Paste")
			(net "HSC_D_OC_3")
		)
		(pad "4" smd rect
			(at -2.237486 -0.249936 270)
			(size 0.254 0.381)
			(layers "F.Cu" "F.Mask" "F.Paste")
			(net "HSC_ON")
		)
		(pad "5" smd rect
			(at -2.237486 0.249936 270)
			(size 0.254 0.381)
			(layers "F.Cu" "F.Mask" "F.Paste")
			(net "HSC_FAULT")
		)
		(pad "6" smd rect
			(at -2.237486 0.750062 270)
			(size 0.254 0.381)
			(layers "F.Cu" "F.Mask" "F.Paste")
			(net "HSC_FLT_TYPE_3")
		)
		(pad "7" smd rect
			(at -2.237486 1.249934 270)
			(size 0.254 0.381)
			(layers "F.Cu" "F.Mask" "F.Paste")
			(net "HSC_NC1_3")
		)
		(pad "8" smd rect
			(at -2.250186 1.75006 270)
			(size 0.254 0.3556)
			(layers "F.Cu" "F.Mask" "F.Paste")
			(net "HSC_MODE_3")
		)
		(pad "9" smd rect
			(at -1.75006 2.250186 180)
			(size 0.254 0.3556)
			(layers "F.Cu" "F.Mask" "F.Paste")
			(net "P12V_PSU")
		)
		(pad "10" smd rect
			(at -1.249934 2.237486 180)
			(size 0.254 0.381)
			(layers "F.Cu" "F.Mask" "F.Paste")
			(net "P12V_PSU")
		)
		(pad "11" smd rect
			(at -0.750062 2.237486 180)
			(size 0.254 0.381)
			(layers "F.Cu" "F.Mask" "F.Paste")
			(net "P12V_PSU")
		)
		(pad "12" smd rect
			(at -0.249936 2.237486 180)
			(size 0.254 0.381)
			(layers "F.Cu" "F.Mask" "F.Paste")
			(net "P12V_PSU")
		)
		(pad "13" smd rect
			(at 0.249936 2.237486 180)
			(size 0.254 0.381)
			(layers "F.Cu" "F.Mask" "F.Paste")
			(net "P12V_PSU")
		)
		(pad "14" smd rect
			(at 0.750062 2.237486 180)
			(size 0.254 0.381)
			(layers "F.Cu" "F.Mask" "F.Paste")
			(net "P12V_PSU")
		)
		(pad "15" smd rect
			(at 1.249934 2.237486 180)
			(size 0.254 0.381)
			(layers "F.Cu" "F.Mask" "F.Paste")
			(net "P12V_PSU")
		)
		(pad "16" smd rect
			(at 1.75006 2.250186 180)
			(size 0.254 0.3556)
			(layers "F.Cu" "F.Mask" "F.Paste")
			(net "P12V_PSU")
		)
		(pad "17" smd rect
			(at 2.250186 1.75006 270)
			(size 0.254 0.3556)
			(layers "F.Cu" "F.Mask" "F.Paste")
			(net "HSC_SCREF_3")
		)
		(pad "18" smd rect
			(at 2.237486 1.249934 270)
			(size 0.254 0.381)
			(layers "F.Cu" "F.Mask" "F.Paste")
			(net "HSC_VTEMP")
		)
		(pad "19" smd rect
			(at 2.237486 0.750062 270)
			(size 0.254 0.381)
			(layers "F.Cu" "F.Mask" "F.Paste")
			(net "HSC_SS")
		)
		(pad "20" smd rect
			(at 2.237486 0.249936 270)
			(size 0.254 0.381)
			(layers "F.Cu" "F.Mask" "F.Paste")
			(net "AGND_HSC")
		)
		(pad "21" smd rect
			(at 2.237486 -0.249936 270)
			(size 0.254 0.381)
			(layers "F.Cu" "F.Mask" "F.Paste")
			(net "HSC_VDD_R_3")
		)
		(pad "22" smd rect
			(at 2.237486 -0.750062 270)
			(size 0.254 0.381)
			(layers "F.Cu" "F.Mask" "F.Paste")
			(net "HSC_IMON")
		)
		(pad "23" smd rect
			(at 2.237486 -1.249934 270)
			(size 0.254 0.381)
			(layers "F.Cu" "F.Mask" "F.Paste")
			(net "HSC_CS_3")
		)
		(pad "24" smd rect
			(at 2.250186 -1.75006 270)
			(size 0.254 0.3556)
			(layers "F.Cu" "F.Mask" "F.Paste")
			(net "HSC_OCREF")
		)
		(pad "25" smd rect
			(at 1.75006 -2.250186 180)
			(size 0.254 0.3556)
			(layers "F.Cu" "F.Mask" "F.Paste")
			(net "P12V_AUX")
		)
		(pad "26" smd rect
			(at 1.249934 -2.237486 180)
			(size 0.254 0.381)
			(layers "F.Cu" "F.Mask" "F.Paste")
			(net "P12V_AUX")
		)
		(pad "27" smd rect
			(at 0.750062 -2.237486 180)
			(size 0.254 0.381)
			(layers "F.Cu" "F.Mask" "F.Paste")
			(net "P12V_AUX")
		)
		(pad "28" smd rect
			(at 0.249936 -2.237486 180)
			(size 0.254 0.381)
			(layers "F.Cu" "F.Mask" "F.Paste")
			(net "P12V_AUX")
		)
		(pad "29" smd rect
			(at -0.249936 -2.237486 180)
			(size 0.254 0.381)
			(layers "F.Cu" "F.Mask" "F.Paste")
			(net "P12V_AUX")
		)
		(pad "30" smd rect
			(at -0.750062 -2.237486 180)
			(size 0.254 0.381)
			(layers "F.Cu" "F.Mask" "F.Paste")
			(net "P12V_AUX")
		)
		(pad "31" smd rect
			(at -1.249934 -2.237486 180)
			(size 0.254 0.381)
			(layers "F.Cu" "F.Mask" "F.Paste")
			(net "P12V_AUX")
		)
		(pad "32" smd rect
			(at -1.75006 -2.250186 180)
			(size 0.254 0.3556)
			(layers "F.Cu" "F.Mask" "F.Paste")
			(net "P12V_AUX")
		)
		(pad "33" smd rect
			(at 0 0 180)
			(size 3.4036 3.4036)
			(layers "F.Cu" "F.Mask" "F.Paste")
			(net "P12V_PSU")
		)
		(zone
			(layer "F.Cu")
			(hatch none 0.5)
			(connect_pads
				(clearance 0)
			)
			(min_thickness 0.25)
			(keepout
				(tracks not_allowed)
				(vias allowed)
				(pads allowed)
				(copperpour not_allowed)
				(footprints allowed)
			)
			(placement
				(enabled no)
				(sheetname "")
			)
			(fill
				(thermal_gap 0.5)
				(thermal_bridge_width 0.5)
				(island_removal_mode 0)
			)
			(polygon
				(pts
					(xy 218.850972 -403.5806) (xy 219.119958 -403.5806) (xy 219.119958 -400.167602) (xy 222.625158 -400.167602)
					(xy 222.625158 -402.428202) (xy 222.868744 -402.428202) (xy 222.868744 -400.472402) (xy 222.894144 -400.472402)
					(xy 222.894144 -399.898616) (xy 222.320358 -399.898616) (xy 222.320358 -399.924016) (xy 219.424758 -399.924016)
					(xy 219.424758 -399.898616) (xy 218.850972 -399.898616) (xy 218.850972 -400.472402) (xy 218.876372 -400.472402)
					(xy 218.876372 -403.368002) (xy 218.850972 -403.368002)
				)
			)
		)
	)
	(footprint ""
		(layer "F.Cu")
		(at 365.835692 -258.405122 180)
		(property "Reference" "C2571"
			(at 0 0 180)
			(layer "F.SilkS")
			(hide yes)
			(effects
				(font
					(size 1.27 1.27)
				)
			)
		)
		(property "Value" ""
			(at 0 0 180)
			(layer "F.Fab")
			(effects
				(font
					(size 1.27 1.27)
				)
			)
		)
		(duplicate_pad_numbers_are_jumpers no)
		(fp_line
			(start 0.7874 0.4064)
			(end -0.7874 0.4064)
			(stroke
				(width 0.1524)
				(type default)
			)
			(layer "F.SilkS")
		)
		(fp_line
			(start 0.7874 -0.4064)
			(end 0.7874 0.4064)
			(stroke
				(width 0.1524)
				(type default)
			)
			(layer "F.SilkS")
		)
		(fp_line
			(start -0.7874 0.4064)
			(end -0.7874 -0.4064)
			(stroke
				(width 0.1524)
				(type default)
			)
			(layer "F.SilkS")
		)
		(fp_line
			(start -0.7874 -0.4064)
			(end 0.7874 -0.4064)
			(stroke
				(width 0.1524)
				(type default)
			)
			(layer "F.SilkS")
		)
		(fp_line
			(start 0.67945 0.3048)
			(end 0.120396 0.3048)
			(stroke
				(width 0.1)
				(type default)
			)
			(layer "F.Fab")
		)
		(fp_line
			(start 0.67945 -0.3048)
			(end 0.67945 0.3048)
			(stroke
				(width 0.1)
				(type default)
			)
			(layer "F.Fab")
		)
		(fp_line
			(start 0.12065 -0.2794)
			(end 0.12065 -0.3048)
			(stroke
				(width 0.1)
				(type default)
			)
			(layer "F.Fab")
		)
		(fp_line
			(start 0.12065 -0.3048)
			(end 0.67945 -0.3048)
			(stroke
				(width 0.1)
				(type default)
			)
			(layer "F.Fab")
		)
		(fp_line
			(start 0.120396 0.3048)
			(end 0.120396 0.2794)
			(stroke
				(width 0.1)
				(type default)
			)
			(layer "F.Fab")
		)
		(fp_line
			(start 0.120396 0.2794)
			(end -0.12065 0.2794)
			(stroke
				(width 0.1)
				(type default)
			)
			(layer "F.Fab")
		)
		(fp_line
			(start -0.12065 0.3048)
			(end -0.67945 0.3048)
			(stroke
				(width 0.1)
				(type default)
			)
			(layer "F.Fab")
		)
		(fp_line
			(start -0.12065 0.2794)
			(end -0.12065 0.3048)
			(stroke
				(width 0.1)
				(type default)
			)
			(layer "F.Fab")
		)
		(fp_line
			(start -0.12065 -0.2794)
			(end 0.12065 -0.2794)
			(stroke
				(width 0.1)
				(type default)
			)
			(layer "F.Fab")
		)
		(fp_line
			(start -0.12065 -0.305054)
			(end -0.12065 -0.2794)
			(stroke
				(width 0.1)
				(type default)
			)
			(layer "F.Fab")
		)
		(fp_line
			(start -0.67945 0.3048)
			(end -0.67945 -0.305054)
			(stroke
				(width 0.1)
				(type default)
			)
			(layer "F.Fab")
		)
		(fp_line
			(start -0.67945 -0.305054)
			(end -0.12065 -0.305054)
			(stroke
				(width 0.1)
				(type default)
			)
			(layer "F.Fab")
		)
		(pad "1" smd circle
			(at -0.40005 0 180)
			(size 0 0)
			(layers "F.Cu" "F.Mask" "F.Paste")
			(net "PVDDCR_SOC_P0")
		)
		(pad "2" smd circle
			(at 0.40005 0 180)
			(size 0 0)
			(layers "F.Cu" "F.Mask" "F.Paste")
			(net "GND")
		)
	)
	(footprint ""
		(layer "F.Cu")
		(at 108.355892 -258.795266)
		(property "Reference" "C2478"
			(at 0 0 0)
			(layer "F.SilkS")
			(hide yes)
			(effects
				(font
					(size 1.27 1.27)
				)
			)
		)
		(property "Value" ""
			(at 0 0 0)
			(layer "F.Fab")
			(effects
				(font
					(size 1.27 1.27)
				)
			)
		)
		(duplicate_pad_numbers_are_jumpers no)
		(fp_line
			(start -0.7874 -0.4064)
			(end 0.7874 -0.4064)
			(stroke
				(width 0.1524)
				(type default)
			)
			(layer "F.SilkS")
		)
		(fp_line
			(start -0.7874 0.4064)
			(end -0.7874 -0.4064)
			(stroke
				(width 0.1524)
				(type default)
			)
			(layer "F.SilkS")
		)
		(fp_line
			(start 0.7874 -0.4064)
			(end 0.7874 0.4064)
			(stroke
				(width 0.1524)
				(type default)
			)
			(layer "F.SilkS")
		)
		(fp_line
			(start 0.7874 0.4064)
			(end -0.7874 0.4064)
			(stroke
				(width 0.1524)
				(type default)
			)
			(layer "F.SilkS")
		)
		(fp_line
			(start -0.67945 -0.305054)
			(end -0.12065 -0.305054)
			(stroke
				(width 0.1)
				(type default)
			)
			(layer "F.Fab")
		)
		(fp_line
			(start -0.67945 0.3048)
			(end -0.67945 -0.305054)
			(stroke
				(width 0.1)
				(type default)
			)
			(layer "F.Fab")
		)
		(fp_line
			(start -0.12065 -0.305054)
			(end -0.12065 -0.2794)
			(stroke
				(width 0.1)
				(type default)
			)
			(layer "F.Fab")
		)
		(fp_line
			(start -0.12065 -0.2794)
			(end 0.12065 -0.2794)
			(stroke
				(width 0.1)
				(type default)
			)
			(layer "F.Fab")
		)
		(fp_line
			(start -0.12065 0.2794)
			(end -0.12065 0.3048)
			(stroke
				(width 0.1)
				(type default)
			)
			(layer "F.Fab")
		)
		(fp_line
			(start -0.12065 0.3048)
			(end -0.67945 0.3048)
			(stroke
				(width 0.1)
				(type default)
			)
			(layer "F.Fab")
		)
		(fp_line
			(start 0.120396 0.2794)
			(end -0.12065 0.2794)
			(stroke
				(width 0.1)
				(type default)
			)
			(layer "F.Fab")
		)
		(fp_line
			(start 0.120396 0.3048)
			(end 0.120396 0.2794)
			(stroke
				(width 0.1)
				(type default)
			)
			(layer "F.Fab")
		)
		(fp_line
			(start 0.12065 -0.3048)
			(end 0.67945 -0.3048)
			(stroke
				(width 0.1)
				(type default)
			)
			(layer "F.Fab")
		)
		(fp_line
			(start 0.12065 -0.2794)
			(end 0.12065 -0.3048)
			(stroke
				(width 0.1)
				(type default)
			)
			(layer "F.Fab")
		)
		(fp_line
			(start 0.67945 -0.3048)
			(end 0.67945 0.3048)
			(stroke
				(width 0.1)
				(type default)
			)
			(layer "F.Fab")
		)
		(fp_line
			(start 0.67945 0.3048)
			(end 0.120396 0.3048)
			(stroke
				(width 0.1)
				(type default)
			)
			(layer "F.Fab")
		)
		(pad "1" smd circle
			(at -0.40005 0)
			(size 0 0)
			(layers "F.Cu" "F.Mask" "F.Paste")
			(net "PVDDIO_P1")
		)
		(pad "2" smd circle
			(at 0.40005 0)
			(size 0 0)
			(layers "F.Cu" "F.Mask" "F.Paste")
			(net "GND")
		)
	)
	(footprint ""
		(layer "F.Cu")
		(at 38.180772 -55.869332 -90)
		(property "Reference" "R8025"
			(at 0 0 270)
			(layer "F.SilkS")
			(hide yes)
			(effects
				(font
					(size 1.27 1.27)
				)
			)
		)
		(property "Value" ""
			(at 0 0 270)
			(layer "F.Fab")
			(effects
				(font
					(size 1.27 1.27)
				)
			)
		)
		(duplicate_pad_numbers_are_jumpers no)
		(fp_line
			(start -0.7874 0.4064)
			(end -0.7874 -0.4064)
			(stroke
				(width 0.1524)
				(type default)
			)
			(layer "F.SilkS")
		)
		(fp_line
			(start 0.7874 0.4064)
			(end -0.7874 0.4064)
			(stroke
				(width 0.1524)
				(type default)
			)
			(layer "F.SilkS")
		)
		(fp_line
			(start -0.7874 -0.4064)
			(end 0.7874 -0.4064)
			(stroke
				(width 0.1524)
				(type default)
			)
			(layer "F.SilkS")
		)
		(fp_line
			(start 0.7874 -0.4064)
			(end 0.7874 0.4064)
			(stroke
				(width 0.1524)
				(type default)
			)
			(layer "F.SilkS")
		)
		(fp_line
			(start -0.67945 0.3048)
			(end -0.67945 -0.305054)
			(stroke
				(width 0.1)
				(type default)
			)
			(layer "F.Fab")
		)
		(fp_line
			(start -0.12065 0.3048)
			(end -0.67945 0.3048)
			(stroke
				(width 0.1)
				(type default)
			)
			(layer "F.Fab")
		)
		(fp_line
			(start 0.120396 0.3048)
			(end 0.120396 0.2794)
			(stroke
				(width 0.1)
				(type default)
			)
			(layer "F.Fab")
		)
		(fp_line
			(start 0.67945 0.3048)
			(end 0.120396 0.3048)
			(stroke
				(width 0.1)
				(type default)
			)
			(layer "F.Fab")
		)
		(fp_line
			(start -0.12065 0.2794)
			(end -0.12065 0.3048)
			(stroke
				(width 0.1)
				(type default)
			)
			(layer "F.Fab")
		)
		(fp_line
			(start 0.120396 0.2794)
			(end -0.12065 0.2794)
			(stroke
				(width 0.1)
				(type default)
			)
			(layer "F.Fab")
		)
		(fp_line
			(start -0.12065 -0.2794)
			(end 0.12065 -0.2794)
			(stroke
				(width 0.1)
				(type default)
			)
			(layer "F.Fab")
		)
		(fp_line
			(start 0.12065 -0.2794)
			(end 0.12065 -0.3048)
			(stroke
				(width 0.1)
				(type default)
			)
			(layer "F.Fab")
		)
		(fp_line
			(start 0.12065 -0.3048)
			(end 0.67945 -0.3048)
			(stroke
				(width 0.1)
				(type default)
			)
			(layer "F.Fab")
		)
		(fp_line
			(start 0.67945 -0.3048)
			(end 0.67945 0.3048)
			(stroke
				(width 0.1)
				(type default)
			)
			(layer "F.Fab")
		)
		(fp_line
			(start -0.67945 -0.305054)
			(end -0.12065 -0.305054)
			(stroke
				(width 0.1)
				(type default)
			)
			(layer "F.Fab")
		)
		(fp_line
			(start -0.12065 -0.305054)
			(end -0.12065 -0.2794)
			(stroke
				(width 0.1)
				(type default)
			)
			(layer "F.Fab")
		)
		(pad "1" smd circle
			(at -0.40005 0 270)
			(size 0 0)
			(layers "F.Cu" "F.Mask" "F.Paste")
			(net "LED_P12V_PSU_R1")
		)
		(pad "2" smd circle
			(at 0.40005 0 270)
			(size 0 0)
			(layers "F.Cu" "F.Mask" "F.Paste")
			(net "LED_P12V_PSU_R2")
		)
	)
)
